(kicad_pcb
	(version 20241229)
	(generator "pcbnew")
	(generator_version "9.0")
	(general
		(thickness 1.6)
		(legacy_teardrops no)
	)
	(paper "A4")
	(title_block
		(title "LPDDR4 testbed")
		(date "2024-03-26")
		(rev "1.2.2")
		(comment 9 "footprints 35-39 of 66")
	)
	(layers
		(0 "F.Cu" signal)
		(4 "In1.Cu" power)
		(6 "In2.Cu" power)
		(8 "In3.Cu" signal)
		(10 "In4.Cu" signal)
		(2 "B.Cu" signal)
		(9 "F.Adhes" user "F.Adhesive")
		(11 "B.Adhes" user "B.Adhesive")
		(13 "F.Paste" user)
		(15 "B.Paste" user)
		(5 "F.SilkS" user "F.Silkscreen")
		(7 "B.SilkS" user "B.Silkscreen")
		(1 "F.Mask" user)
		(3 "B.Mask" user)
		(17 "Dwgs.User" user "User.Drawings")
		(19 "Cmts.User" user "User.Comments")
		(21 "Eco1.User" user "User.Eco1")
		(23 "Eco2.User" user "User.Eco2")
		(25 "Edge.Cuts" user)
		(27 "Margin" user)
		(31 "F.CrtYd" user "F.Courtyard")
		(29 "B.CrtYd" user "B.Courtyard")
		(35 "F.Fab" user)
		(33 "B.Fab" user)
	)
	(footprint "antmicro-footprints:R_0402_1005Metric"
		(layer "F.Cu")
		(at 133.075 75.95 90)
		(descr "Resistor SMD 0402")
		(tags "resistor SMD 0402")
		(property "Reference" "R12"
			(at -1 -0.5 90)
			(layer "F.SilkS")
			(effects
				(font
					(size 0.7 0.7)
					(thickness 0.15)
				)
				(justify left bottom)
			)
		)
		(property "Value" "R_220R_0402"
			(at 0 1.4 90)
			(layer "F.Fab")
			(effects
				(font
					(size 0.7 0.7)
					(thickness 0.15)
				)
				(justify left bottom)
			)
		)
		(property "Description" "220R resistor in 0402 package with 1% tolerance"
			(at 0 0 90)
			(layer "F.Fab")
			(hide yes)
			(effects
				(font
					(size 1.27 1.27)
					(thickness 0.15)
				)
			)
		)
		(property "Author" "Antmicro"
			(at 209.025 -57.125 0)
			(layer "F.Fab")
			(hide yes)
			(effects
				(font
					(size 1 1)
					(thickness 0.15)
				)
			)
		)
		(property "License" "Apache-2.0"
			(at 209.025 -57.125 0)
			(layer "F.Fab")
			(hide yes)
			(effects
				(font
					(size 1 1)
					(thickness 0.15)
				)
			)
		)
		(property "MPN" "ERJ2GEJ221X"
			(at 209.025 -57.125 0)
			(layer "F.Fab")
			(hide yes)
			(effects
				(font
					(size 1 1)
					(thickness 0.15)
				)
			)
		)
		(property "Manufacturer" "Panasonic"
			(at 209.025 -57.125 0)
			(layer "F.Fab")
			(hide yes)
			(effects
				(font
					(size 1 1)
					(thickness 0.15)
				)
			)
		)
		(property "Tolerance" "1%"
			(at 209.025 -57.125 0)
			(layer "F.Fab")
			(hide yes)
			(effects
				(font
					(size 1 1)
					(thickness 0.15)
				)
			)
		)
		(property "Val" "220R"
			(at 209.025 -57.125 0)
			(layer "F.Fab")
			(hide yes)
			(effects
				(font
					(size 1 1)
					(thickness 0.15)
				)
			)
		)
		(sheetname "EEPROM")
		(sheetfile "EEPROM.kicad_sch")
		(attr smd)
		(fp_rect
			(start -0.93 -0.47)
			(end 0.93 0.47)
			(stroke
				(width 0.05)
				(type solid)
			)
			(fill no)
			(layer "F.CrtYd")
		)
		(fp_rect
			(start -0.5 -0.25)
			(end 0.5 0.25)
			(stroke
				(width 0.15)
				(type solid)
			)
			(fill no)
			(layer "F.Fab")
		)
		(pad "1" smd roundrect
			(at -0.485 0 90)
			(size 0.59 0.64)
			(layers "F.Cu" "F.Mask" "F.Paste")
			(roundrect_rratio 0.25)
			(net 151 "Net-(IC1-P3)")
			(pintype "passive")
		)
		(pad "2" smd roundrect
			(at 0.485 0 90)
			(size 0.59 0.64)
			(layers "F.Cu" "F.Mask" "F.Paste")
			(roundrect_rratio 0.25)
			(net 258 "Net-(D4-Pad1)")
			(pintype "passive")
		)
	)
	(footprint "antmicro-footprints:TP_SMD_0.75mm"
		(layer "F.Cu")
		(at 129.55 88.55)
		(property "Reference" "TP2"
			(at -1.075 -0.35 0)
			(layer "F.SilkS")
			(effects
				(font
					(size 0.7 0.7)
					(thickness 0.15)
				)
				(justify left bottom)
			)
		)
		(property "Value" "TP_0.75mm_SMD"
			(at 0 1.2 0)
			(layer "F.Fab")
			(effects
				(font
					(size 0.7 0.7)
					(thickness 0.15)
				)
				(justify left bottom)
			)
		)
		(property "Description" "Test Point 0.75mm"
			(at 0 0 0)
			(layer "F.Fab")
			(hide yes)
			(effects
				(font
					(size 1.27 1.27)
					(thickness 0.15)
				)
			)
		)
		(property "Author" "Antmicro"
			(at 0 0 0)
			(layer "F.Fab")
			(hide yes)
			(effects
				(font
					(size 1 1)
					(thickness 0.15)
				)
			)
		)
		(property "License" "Apache-2.0"
			(at 0 0 0)
			(layer "F.Fab")
			(hide yes)
			(effects
				(font
					(size 1 1)
					(thickness 0.15)
				)
			)
		)
		(property "MPN" ""
			(at 0 0 0)
			(layer "F.Fab")
			(hide yes)
			(effects
				(font
					(size 1 1)
					(thickness 0.15)
				)
			)
		)
		(property "Manufacturer" ""
			(at 0 0 0)
			(layer "F.Fab")
			(hide yes)
			(effects
				(font
					(size 1 1)
					(thickness 0.15)
				)
			)
		)
		(sheetname "EEPROM")
		(sheetfile "EEPROM.kicad_sch")
		(attr exclude_from_pos_files)
		(pad "1" smd circle
			(at 0 0)
			(size 0.75 0.75)
			(layers "F.Cu" "F.Mask")
			(net 153 "Net-(IC1-P5)")
			(pinfunction "1")
			(pintype "passive")
		)
	)
	(footprint "antmicro-footprints:TP_SMD_0.75mm"
		(layer "F.Cu")
		(at 131.125 88.55)
		(property "Reference" "TP3"
			(at 0.45 0.4 0)
			(layer "F.SilkS")
			(effects
				(font
					(size 0.7 0.7)
					(thickness 0.15)
				)
				(justify left bottom)
			)
		)
		(property "Value" "TP_0.75mm_SMD"
			(at 0 1.2 0)
			(layer "F.Fab")
			(effects
				(font
					(size 0.7 0.7)
					(thickness 0.15)
				)
				(justify left bottom)
			)
		)
		(property "Description" "Test Point 0.75mm"
			(at 0 0 0)
			(layer "F.Fab")
			(hide yes)
			(effects
				(font
					(size 1.27 1.27)
					(thickness 0.15)
				)
			)
		)
		(property "Author" "Antmicro"
			(at 0 0 0)
			(layer "F.Fab")
			(hide yes)
			(effects
				(font
					(size 1 1)
					(thickness 0.15)
				)
			)
		)
		(property "License" "Apache-2.0"
			(at 0 0 0)
			(layer "F.Fab")
			(hide yes)
			(effects
				(font
					(size 1 1)
					(thickness 0.15)
				)
			)
		)
		(property "MPN" ""
			(at 0 0 0)
			(layer "F.Fab")
			(hide yes)
			(effects
				(font
					(size 1 1)
					(thickness 0.15)
				)
			)
		)
		(property "Manufacturer" ""
			(at 0 0 0)
			(layer "F.Fab")
			(hide yes)
			(effects
				(font
					(size 1 1)
					(thickness 0.15)
				)
			)
		)
		(sheetname "EEPROM")
		(sheetfile "EEPROM.kicad_sch")
		(attr exclude_from_pos_files)
		(pad "1" smd circle
			(at 0 0)
			(size 0.75 0.75)
			(layers "F.Cu" "F.Mask")
			(net 36 "GND")
			(pinfunction "1")
			(pintype "passive")
		)
	)
	(footprint "antmicro-footprints:SOT-23-5"
		(layer "F.Cu")
		(at 131.575 83.55 180)
		(property "Reference" "U2"
			(at -0.4 2 180)
			(layer "F.SilkS")
			(effects
				(font
					(size 0.7 0.7)
					(thickness 0.15)
				)
				(justify left bottom)
			)
		)
		(property "Value" "TPS613221A_SOT-23-5"
			(at 0.002 2.799 180)
			(layer "F.Fab")
			(effects
				(font
					(size 0.7 0.7)
					(thickness 0.15)
				)
				(justify left bottom)
			)
		)
		(property "Description" "1.8-A switch current boost converter 6.5-μA Quiescent current"
			(at 0 0 180)
			(layer "F.Fab")
			(hide yes)
			(effects
				(font
					(size 1.27 1.27)
					(thickness 0.15)
				)
			)
		)
		(property "Author" "Antmicro"
			(at 263.15 167.1 0)
			(layer "F.Fab")
			(hide yes)
			(effects
				(font
					(size 1 1)
					(thickness 0.15)
				)
			)
		)
		(property "License" "Apache-2.0"
			(at 263.15 167.1 0)
			(layer "F.Fab")
			(hide yes)
			(effects
				(font
					(size 1 1)
					(thickness 0.15)
				)
			)
		)
		(property "MPN" "TPS613221ADBVT"
			(at 263.15 167.1 0)
			(layer "F.Fab")
			(hide yes)
			(effects
				(font
					(size 1 1)
					(thickness 0.15)
				)
			)
		)
		(property "Manufacturer" "Texas Instruments"
			(at 263.15 167.1 0)
			(layer "F.Fab")
			(hide yes)
			(effects
				(font
					(size 1 1)
					(thickness 0.15)
				)
			)
		)
		(sheetname "EEPROM")
		(sheetfile "EEPROM.kicad_sch")
		(attr smd)
		(fp_line
			(start 0.8 1.599)
			(end 0.549 1.599)
			(stroke
				(width 0.15)
				(type solid)
			)
			(layer "F.SilkS")
		)
		(fp_line
			(start 0.8 1.3)
			(end 0.8 1.599)
			(stroke
				(width 0.15)
				(type solid)
			)
			(layer "F.SilkS")
		)
		(fp_line
			(start 0.8 0.55)
			(end 0.8 -0.55)
			(stroke
				(width 0.15)
				(type solid)
			)
			(layer "F.SilkS")
		)
		(fp_line
			(start 0.8 -1.3)
			(end 0.8 -1.6)
			(stroke
				(width 0.15)
				(type solid)
			)
			(layer "F.SilkS")
		)
		(fp_line
			(start 0.8 -1.6)
			(end 0.5 -1.6)
			(stroke
				(width 0.15)
				(type solid)
			)
			(layer "F.SilkS")
		)
		(fp_line
			(start -0.55 1.6)
			(end -0.85 1.6)
			(stroke
				(width 0.15)
				(type solid)
			)
			(layer "F.SilkS")
		)
		(fp_line
			(start -0.8 -1.6)
			(end -0.5 -1.6)
			(stroke
				(width 0.15)
				(type solid)
			)
			(layer "F.SilkS")
		)
		(fp_line
			(start -0.8 -1.6)
			(end -0.8 -1.3)
			(stroke
				(width 0.15)
				(type solid)
			)
			(layer "F.SilkS")
		)
		(fp_line
			(start -0.85 1.6)
			(end -0.85 1.301)
			(stroke
				(width 0.15)
				(type solid)
			)
			(layer "F.SilkS")
		)
		(fp_circle
			(center -1.25 -1.5)
			(end -1.2 -1.5)
			(stroke
				(width 0.15)
				(type solid)
			)
			(fill yes)
			(layer "F.SilkS")
		)
		(fp_rect
			(start 1.9 -1.76)
			(end -1.9 1.75)
			(stroke
				(width 0.05)
				(type solid)
			)
			(fill no)
			(layer "F.CrtYd")
		)
		(fp_line
			(start -0.398 -1.526)
			(end -0.874 -1.05)
			(stroke
				(width 0.15)
				(type solid)
			)
			(layer "F.Fab")
		)
		(fp_rect
			(start 0.874 1.523)
			(end -0.873 -1.525)
			(stroke
				(width 0.15)
				(type solid)
			)
			(fill no)
			(layer "F.Fab")
		)
		(pad "1" smd rect
			(at -1.351 -0.951 90)
			(size 0.55 1)
			(layers "F.Cu" "F.Mask" "F.Paste")
			(net 157 "Net-(U2-SW)")
			(pinfunction "SW")
			(pintype "power_in")
		)
		(pad "2" smd rect
			(at -1.351 0 90)
			(size 0.55 1)
			(layers "F.Cu" "F.Mask" "F.Paste")
			(net 36 "GND")
			(pinfunction "GND")
			(pintype "power_in")
		)
		(pad "3" smd rect
			(at -1.351 0.949 90)
			(size 0.55 1)
			(layers "F.Cu" "F.Mask" "F.Paste")
			(net 260 "unconnected-(U2-NC-Pad3)")
			(pinfunction "NC")
			(pintype "no_connect")
		)
		(pad "4" smd rect
			(at 1.35 0.949 90)
			(size 0.55 1)
			(layers "F.Cu" "F.Mask" "F.Paste")
			(net 241 "VDDLED")
			(pinfunction "VOUT")
			(pintype "power_in")
		)
		(pad "5" smd rect
			(at 1.35 -0.951 90)
			(size 0.55 1)
			(layers "F.Cu" "F.Mask" "F.Paste")
			(net 261 "unconnected-(U2-NC-Pad5)")
			(pinfunction "NC")
			(pintype "no_connect")
		)
	)
	(footprint "antmicro-footprints:TSSOP-16_4.4x5mm_P0.65mm"
		(layer "F.Cu")
		(at 125.125 84.9)
		(property "Reference" "IC1"
			(at 0 -2.952 0)
			(layer "F.SilkS")
			(effects
				(font
					(size 0.7 0.7)
					(thickness 0.15)
				)
				(justify left bottom)
			)
		)
		(property "Value" "PCA6408A_TSSOP"
			(at 0 3.749 0)
			(layer "F.Fab")
			(effects
				(font
					(size 0.7 0.7)
					(thickness 0.15)
				)
				(justify left bottom)
			)
		)
		(property "Description" "Low-voltage, 8-bit I2C-bus and SMBus I/O expander"
			(at 0 0 0)
			(layer "F.Fab")
			(hide yes)
			(effects
				(font
					(size 1.27 1.27)
					(thickness 0.15)
				)
			)
		)
		(property "Author" "Antmicro"
			(at 0 0 0)
			(layer "F.Fab")
			(hide yes)
			(effects
				(font
					(size 1 1)
					(thickness 0.15)
				)
			)
		)
		(property "License" "Apache-2.0"
			(at 0 0 0)
			(layer "F.Fab")
			(hide yes)
			(effects
				(font
					(size 1 1)
					(thickness 0.15)
				)
			)
		)
		(property "MPN" "PCA6408APW"
			(at 0 0 0)
			(layer "F.Fab")
			(hide yes)
			(effects
				(font
					(size 1 1)
					(thickness 0.15)
				)
			)
		)
		(property "Manufacturer" "NXP"
			(at 0 0 0)
			(layer "F.Fab")
			(hide yes)
			(effects
				(font
					(size 1 1)
					(thickness 0.15)
				)
			)
		)
		(sheetname "EEPROM")
		(sheetfile "EEPROM.kicad_sch")
		(attr smd)
		(fp_line
			(start -2.149 -2.735)
			(end 2.25 -2.735)
			(stroke
				(width 0.15)
				(type solid)
			)
			(layer "F.SilkS")
		)
		(fp_line
			(start 0.051 2.733)
			(end -2.149 2.733)
			(stroke
				(width 0.15)
				(type solid)
			)
			(layer "F.SilkS")
		)
		(fp_line
			(start 0.051 2.733)
			(end 2.25 2.733)
			(stroke
				(width 0.15)
				(type solid)
			)
			(layer "F.SilkS")
		)
		(fp_circle
			(center -2.815 -3.05)
			(end -2.765 -3.05)
			(stroke
				(width 0.15)
				(type solid)
			)
			(fill yes)
			(layer "F.SilkS")
		)
		(fp_line
			(start -3.81 -2.75)
			(end -3.81 2.74)
			(stroke
				(width 0.05)
				(type solid)
			)
			(layer "F.CrtYd")
		)
		(fp_line
			(start -3.81 2.74)
			(end 3.89 2.74)
			(stroke
				(width 0.05)
				(type solid)
			)
			(layer "F.CrtYd")
		)
		(fp_line
			(start 3.89 -2.75)
			(end -3.81 -2.75)
			(stroke
				(width 0.05)
				(type solid)
			)
			(layer "F.CrtYd")
		)
		(fp_line
			(start 3.89 2.74)
			(end 3.89 -2.75)
			(stroke
				(width 0.05)
				(type solid)
			)
			(layer "F.CrtYd")
		)
		(fp_line
			(start -2.149 -1.5)
			(end -1.15 -2.5)
			(stroke
				(width 0.15)
				(type solid)
			)
			(layer "F.Fab")
		)
		(fp_line
			(start -2.149 2.499)
			(end -2.149 -1.5)
			(stroke
				(width 0.15)
				(type solid)
			)
			(layer "F.Fab")
		)
		(fp_line
			(start -1.15 -2.5)
			(end 2.25 -2.5)
			(stroke
				(width 0.15)
				(type solid)
			)
			(layer "F.Fab")
		)
		(fp_line
			(start 2.25 -2.5)
			(end 2.25 2.499)
			(stroke
				(width 0.15)
				(type solid)
			)
			(layer "F.Fab")
		)
		(fp_line
			(start 2.25 2.499)
			(end -2.149 2.499)
			(stroke
				(width 0.15)
				(type solid)
			)
			(layer "F.Fab")
		)
		(pad "1" smd rect
			(at -2.815 -2.275)
			(size 1.475 0.4)
			(layers "F.Cu" "F.Mask" "F.Paste")
			(net 187 "VDD1")
			(pinfunction "VDD(I2C)")
			(pintype "power_in")
		)
		(pad "2" smd rect
			(at -2.815 -1.625)
			(size 1.475 0.4)
			(layers "F.Cu" "F.Mask" "F.Paste")
			(net 187 "VDD1")
			(pinfunction "ADDR")
			(pintype "input")
		)
		(pad "3" smd rect
			(at -2.815 -0.975)
			(size 1.475 0.4)
			(layers "F.Cu" "F.Mask" "F.Paste")
			(net 187 "VDD1")
			(pinfunction "~{RESET}")
			(pintype "input")
		)
		(pad "4" smd rect
			(at -2.815 -0.325)
			(size 1.475 0.4)
			(layers "F.Cu" "F.Mask" "F.Paste")
			(net 1 "Net-(IC1-P0)")
			(pinfunction "P0")
			(pintype "bidirectional")
		)
		(pad "5" smd rect
			(at -2.815 0.325)
			(size 1.475 0.4)
			(layers "F.Cu" "F.Mask" "F.Paste")
			(net 2 "Net-(IC1-P1)")
			(pinfunction "P1")
			(pintype "bidirectional")
		)
		(pad "6" smd rect
			(at -2.815 0.975)
			(size 1.475 0.4)
			(layers "F.Cu" "F.Mask" "F.Paste")
			(net 3 "Net-(IC1-P2)")
			(pinfunction "P2")
			(pintype "bidirectional")
		)
		(pad "7" smd rect
			(at -2.815 1.625)
			(size 1.475 0.4)
			(layers "F.Cu" "F.Mask" "F.Paste")
			(net 151 "Net-(IC1-P3)")
			(pinfunction "P3")
			(pintype "bidirectional")
		)
		(pad "8" smd rect
			(at -2.815 2.275)
			(size 1.475 0.4)
			(layers "F.Cu" "F.Mask" "F.Paste")
			(net 36 "GND")
			(pinfunction "GND")
			(pintype "power_in")
		)
		(pad "9" smd rect
			(at 2.91 2.275)
			(size 1.475 0.4)
			(layers "F.Cu" "F.Mask" "F.Paste")
			(net 152 "Net-(IC1-P4)")
			(pinfunction "P4")
			(pintype "bidirectional")
		)
		(pad "10" smd rect
			(at 2.91 1.625)
			(size 1.475 0.4)
			(layers "F.Cu" "F.Mask" "F.Paste")
			(net 153 "Net-(IC1-P5)")
			(pinfunction "P5")
			(pintype "bidirectional")
		)
		(pad "11" smd rect
			(at 2.91 0.975)
			(size 1.475 0.4)
			(layers "F.Cu" "F.Mask" "F.Paste")
			(net 154 "unconnected-(IC1-P6-Pad11)")
			(pinfunction "P6")
			(pintype "bidirectional+no_connect")
		)
		(pad "12" smd rect
			(at 2.91 0.325)
			(size 1.475 0.4)
			(layers "F.Cu" "F.Mask" "F.Paste")
			(net 155 "unconnected-(IC1-P7-Pad12)")
			(pinfunction "P7")
			(pintype "bidirectional+no_connect")
		)
		(pad "13" smd rect
			(at 2.91 -0.325)
			(size 1.475 0.4)
			(layers "F.Cu" "F.Mask" "F.Paste")
			(net 156 "unconnected-(IC1-~{INT}-Pad13)")
			(pinfunction "~{INT}")
			(pintype "open_collector+no_connect")
		)
		(pad "14" smd rect
			(at 2.91 -0.975)
			(size 1.475 0.4)
			(layers "F.Cu" "F.Mask" "F.Paste")
			(net 247 "SCL")
			(pinfunction "SCL")
			(pintype "open_collector")
		)
		(pad "15" smd rect
			(at 2.91 -1.625)
			(size 1.475 0.4)
			(layers "F.Cu" "F.Mask" "F.Paste")
			(net 246 "SDA")
			(pinfunction "SDA")
			(pintype "open_collector")
		)
		(pad "16" smd rect
			(at 2.91 -2.275)
			(size 1.475 0.4)
			(layers "F.Cu" "F.Mask" "F.Paste")
			(net 241 "VDDLED")
			(pinfunction "VDD(P)")
			(pintype "power_in")
		)
	)
)
